(kicad_pcb
	(version 20240108)
	(generator "pcbnew")
	(generator_version "8.0")
	(general
		(thickness 1.62)
		(legacy_teardrops no)
	)
	(paper "A4")
	(title_block
		(title "Jetson Orin Baseboard")
		(date "2025-03-12")
		(rev "1.3.4")
		(company "Antmicro Ltd")
		(comment 1 "www.antmicro.com")
		(comment 9 "footprints 653-657 of 677")
	)
	(layers
		(0 "F.Cu" signal)
		(1 "In1.Cu" signal)
		(2 "In2.Cu" signal)
		(3 "In3.Cu" signal)
		(4 "In4.Cu" jumper)
		(5 "In5.Cu" signal)
		(6 "In6.Cu" signal)
		(31 "B.Cu" signal)
		(32 "B.Adhes" user "B.Adhesive")
		(33 "F.Adhes" user "F.Adhesive")
		(34 "B.Paste" user)
		(35 "F.Paste" user)
		(36 "B.SilkS" user "B.Silkscreen")
		(37 "F.SilkS" user "F.Silkscreen")
		(38 "B.Mask" user)
		(39 "F.Mask" user)
		(40 "Dwgs.User" user "User.Drawings")
		(41 "Cmts.User" user "User.Comments")
		(42 "Eco1.User" user "User.Eco1")
		(43 "Eco2.User" user "User.Eco2")
		(44 "Edge.Cuts" user)
		(45 "Margin" user)
		(46 "B.CrtYd" user "B.Courtyard")
		(47 "F.CrtYd" user "F.Courtyard")
		(48 "B.Fab" user)
		(49 "F.Fab" user)
	)
	(footprint "antmicro-footprints:R_0402_1005Metric"
		(layer "B.Cu")
		(at 57.55 113.45 180)
		(descr "Resistor SMD 0402")
		(tags "resistor SMD 0402")
		(property "Reference" "R59"
			(at -3.08 -0.31 0)
			(layer "B.SilkS")
			(effects
				(font
					(size 0.7 0.7)
					(thickness 0.15)
				)
				(justify left bottom mirror)
			)
		)
		(property "Value" "R_0R_0402"
			(at 0 -1.4 0)
			(layer "B.Fab")
			(effects
				(font
					(size 0.7 0.7)
					(thickness 0.15)
				)
				(justify left bottom mirror)
			)
		)
		(property "Footprint" "antmicro-footprints:R_0402_1005Metric"
			(at 0 0 180)
			(layer "F.Fab")
			(hide yes)
			(effects
				(font
					(size 1.27 1.27)
					(thickness 0.15)
				)
			)
		)
		(property "Datasheet" "https://industrial.panasonic.com/cdbs/www-data/pdf/RDA0000/AOA0000C301.pdf"
			(at 0 0 180)
			(layer "F.Fab")
			(hide yes)
			(effects
				(font
					(size 1.27 1.27)
					(thickness 0.15)
				)
			)
		)
		(property "Author" "Antmicro"
			(at 115.1 226.9 0)
			(layer "B.Fab")
			(hide yes)
			(effects
				(font
					(size 1 1)
					(thickness 0.15)
				)
				(justify mirror)
			)
		)
		(property "Current" "1A"
			(at 115.1 226.9 0)
			(layer "B.Fab")
			(hide yes)
			(effects
				(font
					(size 1 1)
					(thickness 0.15)
				)
				(justify mirror)
			)
		)
		(property "License" "Apache-2.0"
			(at 115.1 226.9 0)
			(layer "B.Fab")
			(hide yes)
			(effects
				(font
					(size 1 1)
					(thickness 0.15)
				)
				(justify mirror)
			)
		)
		(property "MPN" "ERJ2GE0R00X"
			(at 115.1 226.9 0)
			(layer "B.Fab")
			(hide yes)
			(effects
				(font
					(size 1 1)
					(thickness 0.15)
				)
				(justify mirror)
			)
		)
		(property "Manufacturer" "Panasonic"
			(at 115.1 226.9 0)
			(layer "B.Fab")
			(hide yes)
			(effects
				(font
					(size 1 1)
					(thickness 0.15)
				)
				(justify mirror)
			)
		)
		(property "Tolerance" ""
			(at 115.1 226.9 0)
			(layer "B.Fab")
			(hide yes)
			(effects
				(font
					(size 1 1)
					(thickness 0.15)
				)
				(justify mirror)
			)
		)
		(property "Val" "0R"
			(at 115.1 226.9 0)
			(layer "B.Fab")
			(hide yes)
			(effects
				(font
					(size 1 1)
					(thickness 0.15)
				)
				(justify mirror)
			)
		)
		(sheetname "USB Debug, DP")
		(sheetfile "usb.kicad_sch")
		(attr smd exclude_from_pos_files exclude_from_bom dnp)
		(fp_rect
			(start -0.925 0.47)
			(end 0.925 -0.47)
			(stroke
				(width 0.05)
				(type default)
			)
			(fill none)
			(layer "B.CrtYd")
		)
		(fp_rect
			(start -0.5 0.25)
			(end 0.5 -0.25)
			(stroke
				(width 0.15)
				(type solid)
			)
			(fill none)
			(layer "B.Fab")
		)
		(fp_text user "${REFERENCE}"
			(at -0.95 -3.168 0)
			(layer "B.Fab")
			(hide yes)
			(effects
				(font
					(size 0.7 0.7)
					(thickness 0.15)
				)
				(justify left bottom mirror)
			)
		)
		(fp_text user "Author: Antmicro"
			(at -0.95 -4.169 0)
			(layer "B.Fab")
			(hide yes)
			(effects
				(font
					(size 0.7 0.7)
					(thickness 0.15)
				)
				(justify left bottom mirror)
			)
		)
		(fp_text user "License: Apache-2.0"
			(at -0.95 -5.169 0)
			(layer "B.Fab")
			(hide yes)
			(effects
				(font
					(size 0.7 0.7)
					(thickness 0.15)
				)
				(justify left bottom mirror)
			)
		)
		(pad "1" smd roundrect
			(at -0.48 0 180)
			(size 0.59 0.64)
			(layers "B.Cu" "B.Paste" "B.Mask")
			(roundrect_rratio 0.25)
			(net 465 "unconnected-(R59-Pad1)")
			(pintype "passive+no_connect")
		)
		(pad "2" smd roundrect
			(at 0.48 0 180)
			(size 0.59 0.64)
			(layers "B.Cu" "B.Paste" "B.Mask")
			(roundrect_rratio 0.25)
			(net 649 "Net-(U5-~{CTS})")
			(pintype "passive")
		)
	)
	(footprint "antmicro-footprints:R_0402_1005Metric"
		(layer "B.Cu")
		(at 86.6 108.2 180)
		(descr "Resistor SMD 0402")
		(tags "resistor SMD 0402")
		(property "Reference" "R218"
			(at 0.8 -0.475 0)
			(layer "B.SilkS")
			(effects
				(font
					(size 0.7 0.7)
					(thickness 0.15)
				)
				(justify left bottom mirror)
			)
		)
		(property "Value" "R_0R_0402"
			(at 0 -1.4 0)
			(layer "B.Fab")
			(effects
				(font
					(size 0.7 0.7)
					(thickness 0.15)
				)
				(justify left bottom mirror)
			)
		)
		(property "Footprint" "antmicro-footprints:R_0402_1005Metric"
			(at 0 0 180)
			(layer "F.Fab")
			(hide yes)
			(effects
				(font
					(size 1.27 1.27)
					(thickness 0.15)
				)
			)
		)
		(property "Datasheet" "https://industrial.panasonic.com/cdbs/www-data/pdf/RDA0000/AOA0000C301.pdf"
			(at 0 0 180)
			(layer "F.Fab")
			(hide yes)
			(effects
				(font
					(size 1.27 1.27)
					(thickness 0.15)
				)
			)
		)
		(property "Author" "Antmicro"
			(at 173.2 216.4 0)
			(layer "B.Fab")
			(hide yes)
			(effects
				(font
					(size 1 1)
					(thickness 0.15)
				)
				(justify mirror)
			)
		)
		(property "Current" "1A"
			(at 173.2 216.4 0)
			(layer "B.Fab")
			(hide yes)
			(effects
				(font
					(size 1 1)
					(thickness 0.15)
				)
				(justify mirror)
			)
		)
		(property "License" "Apache-2.0"
			(at 173.2 216.4 0)
			(layer "B.Fab")
			(hide yes)
			(effects
				(font
					(size 1 1)
					(thickness 0.15)
				)
				(justify mirror)
			)
		)
		(property "MPN" "ERJ2GE0R00X"
			(at 173.2 216.4 0)
			(layer "B.Fab")
			(hide yes)
			(effects
				(font
					(size 1 1)
					(thickness 0.15)
				)
				(justify mirror)
			)
		)
		(property "Manufacturer" "Panasonic"
			(at 173.2 216.4 0)
			(layer "B.Fab")
			(hide yes)
			(effects
				(font
					(size 1 1)
					(thickness 0.15)
				)
				(justify mirror)
			)
		)
		(property "Tolerance" ""
			(at 173.2 216.4 0)
			(layer "B.Fab")
			(hide yes)
			(effects
				(font
					(size 1 1)
					(thickness 0.15)
				)
				(justify mirror)
			)
		)
		(property "Val" "0R"
			(at 173.2 216.4 0)
			(layer "B.Fab")
			(hide yes)
			(effects
				(font
					(size 1 1)
					(thickness 0.15)
				)
				(justify mirror)
			)
		)
		(sheetname "Peripherals")
		(sheetfile "peripherals.kicad_sch")
		(attr smd)
		(fp_rect
			(start -0.925 0.47)
			(end 0.925 -0.47)
			(stroke
				(width 0.05)
				(type default)
			)
			(fill none)
			(layer "B.CrtYd")
		)
		(fp_rect
			(start -0.5 0.25)
			(end 0.5 -0.25)
			(stroke
				(width 0.15)
				(type solid)
			)
			(fill none)
			(layer "B.Fab")
		)
		(fp_text user "License: Apache-2.0"
			(at -0.95 -5.169 0)
			(layer "B.Fab")
			(hide yes)
			(effects
				(font
					(size 0.7 0.7)
					(thickness 0.15)
				)
				(justify left bottom mirror)
			)
		)
		(fp_text user "${REFERENCE}"
			(at -0.95 -3.168 0)
			(layer "B.Fab")
			(hide yes)
			(effects
				(font
					(size 0.7 0.7)
					(thickness 0.15)
				)
				(justify left bottom mirror)
			)
		)
		(fp_text user "Author: Antmicro"
			(at -0.95 -4.169 0)
			(layer "B.Fab")
			(hide yes)
			(effects
				(font
					(size 0.7 0.7)
					(thickness 0.15)
				)
				(justify left bottom mirror)
			)
		)
		(pad "1" smd roundrect
			(at -0.48 0 180)
			(size 0.59 0.64)
			(layers "B.Cu" "B.Paste" "B.Mask")
			(roundrect_rratio 0.25)
			(net 1 "GND")
			(pintype "passive")
		)
		(pad "2" smd roundrect
			(at 0.48 0 180)
			(size 0.59 0.64)
			(layers "B.Cu" "B.Paste" "B.Mask")
			(roundrect_rratio 0.25)
			(net 352 "/Peripherals/GPIOEX_ADDR")
			(pintype "passive")
		)
	)
	(footprint "antmicro-footprints:R_0402_1005Metric"
		(layer "B.Cu")
		(at 111.6 90.02 90)
		(descr "Resistor SMD 0402")
		(tags "resistor SMD 0402")
		(property "Reference" "R16"
			(at 1.02 1.41 -90)
			(layer "B.SilkS")
			(effects
				(font
					(size 0.7 0.7)
					(thickness 0.15)
				)
				(justify left bottom mirror)
			)
		)
		(property "Value" "R_0R_0402"
			(at 0 -1.4 -90)
			(layer "B.Fab")
			(effects
				(font
					(size 0.7 0.7)
					(thickness 0.15)
				)
				(justify left bottom mirror)
			)
		)
		(property "Footprint" "antmicro-footprints:R_0402_1005Metric"
			(at 0 0 90)
			(layer "F.Fab")
			(hide yes)
			(effects
				(font
					(size 1.27 1.27)
					(thickness 0.15)
				)
			)
		)
		(property "Datasheet" "https://industrial.panasonic.com/cdbs/www-data/pdf/RDA0000/AOA0000C301.pdf"
			(at 0 0 90)
			(layer "F.Fab")
			(hide yes)
			(effects
				(font
					(size 1.27 1.27)
					(thickness 0.15)
				)
			)
		)
		(property "Author" "Antmicro"
			(at 201.62 -21.58 0)
			(layer "B.Fab")
			(hide yes)
			(effects
				(font
					(size 1 1)
					(thickness 0.15)
				)
				(justify mirror)
			)
		)
		(property "Current" "1A"
			(at 201.62 -21.58 0)
			(layer "B.Fab")
			(hide yes)
			(effects
				(font
					(size 1 1)
					(thickness 0.15)
				)
				(justify mirror)
			)
		)
		(property "License" "Apache-2.0"
			(at 201.62 -21.58 0)
			(layer "B.Fab")
			(hide yes)
			(effects
				(font
					(size 1 1)
					(thickness 0.15)
				)
				(justify mirror)
			)
		)
		(property "MPN" "ERJ2GE0R00X"
			(at 201.62 -21.58 0)
			(layer "B.Fab")
			(hide yes)
			(effects
				(font
					(size 1 1)
					(thickness 0.15)
				)
				(justify mirror)
			)
		)
		(property "Manufacturer" "Panasonic"
			(at 201.62 -21.58 0)
			(layer "B.Fab")
			(hide yes)
			(effects
				(font
					(size 1 1)
					(thickness 0.15)
				)
				(justify mirror)
			)
		)
		(property "Tolerance" ""
			(at 201.62 -21.58 0)
			(layer "B.Fab")
			(hide yes)
			(effects
				(font
					(size 1 1)
					(thickness 0.15)
				)
				(justify mirror)
			)
		)
		(property "Val" "0R"
			(at 201.62 -21.58 0)
			(layer "B.Fab")
			(hide yes)
			(effects
				(font
					(size 1 1)
					(thickness 0.15)
				)
				(justify mirror)
			)
		)
		(sheetname "M.2")
		(sheetfile "m-2.kicad_sch")
		(attr smd)
		(fp_rect
			(start -0.925 0.47)
			(end 0.925 -0.47)
			(stroke
				(width 0.05)
				(type default)
			)
			(fill none)
			(layer "B.CrtYd")
		)
		(fp_rect
			(start -0.5 0.25)
			(end 0.5 -0.25)
			(stroke
				(width 0.15)
				(type solid)
			)
			(fill none)
			(layer "B.Fab")
		)
		(fp_text user "Author: Antmicro"
			(at -0.95 -4.169 -90)
			(layer "B.Fab")
			(hide yes)
			(effects
				(font
					(size 0.7 0.7)
					(thickness 0.15)
				)
				(justify left bottom mirror)
			)
		)
		(fp_text user "License: Apache-2.0"
			(at -0.95 -5.169 -90)
			(layer "B.Fab")
			(hide yes)
			(effects
				(font
					(size 0.7 0.7)
					(thickness 0.15)
				)
				(justify left bottom mirror)
			)
		)
		(fp_text user "${REFERENCE}"
			(at -0.95 -3.168 -90)
			(layer "B.Fab")
			(hide yes)
			(effects
				(font
					(size 0.7 0.7)
					(thickness 0.15)
				)
				(justify left bottom mirror)
			)
		)
		(pad "1" smd roundrect
			(at -0.48 0 90)
			(size 0.59 0.64)
			(layers "B.Cu" "B.Paste" "B.Mask")
			(roundrect_rratio 0.25)
			(net 561 "/M.2/PCIE_WAKE_SEL0")
			(pintype "passive")
		)
		(pad "2" smd roundrect
			(at 0.48 0 90)
			(size 0.59 0.64)
			(layers "B.Cu" "B.Paste" "B.Mask")
			(roundrect_rratio 0.25)
			(net 249 "/M.2/~{M2_M_PEWAKE0}")
			(pintype "passive")
		)
	)
	(footprint "antmicro-footprints:R_0402_1005Metric"
		(layer "B.Cu")
		(at 46.9 86.6375 180)
		(descr "Resistor SMD 0402")
		(tags "resistor SMD 0402")
		(property "Reference" "R129"
			(at -0.325 3.4375 0)
			(layer "B.SilkS")
			(effects
				(font
					(size 0.7 0.7)
					(thickness 0.15)
				)
				(justify left bottom mirror)
			)
		)
		(property "Value" "R_0R_0402"
			(at 0 -1.4 0)
			(layer "B.Fab")
			(effects
				(font
					(size 0.7 0.7)
					(thickness 0.15)
				)
				(justify left bottom mirror)
			)
		)
		(property "Footprint" "antmicro-footprints:R_0402_1005Metric"
			(at 0 0 180)
			(layer "F.Fab")
			(hide yes)
			(effects
				(font
					(size 1.27 1.27)
					(thickness 0.15)
				)
			)
		)
		(property "Datasheet" "https://industrial.panasonic.com/cdbs/www-data/pdf/RDA0000/AOA0000C301.pdf"
			(at 0 0 180)
			(layer "F.Fab")
			(hide yes)
			(effects
				(font
					(size 1.27 1.27)
					(thickness 0.15)
				)
			)
		)
		(property "Author" "Antmicro"
			(at 93.8 173.275 0)
			(layer "B.Fab")
			(hide yes)
			(effects
				(font
					(size 1 1)
					(thickness 0.15)
				)
				(justify mirror)
			)
		)
		(property "Current" "1A"
			(at 93.8 173.275 0)
			(layer "B.Fab")
			(hide yes)
			(effects
				(font
					(size 1 1)
					(thickness 0.15)
				)
				(justify mirror)
			)
		)
		(property "License" "Apache-2.0"
			(at 93.8 173.275 0)
			(layer "B.Fab")
			(hide yes)
			(effects
				(font
					(size 1 1)
					(thickness 0.15)
				)
				(justify mirror)
			)
		)
		(property "MPN" "ERJ2GE0R00X"
			(at 93.8 173.275 0)
			(layer "B.Fab")
			(hide yes)
			(effects
				(font
					(size 1 1)
					(thickness 0.15)
				)
				(justify mirror)
			)
		)
		(property "Manufacturer" "Panasonic"
			(at 93.8 173.275 0)
			(layer "B.Fab")
			(hide yes)
			(effects
				(font
					(size 1 1)
					(thickness 0.15)
				)
				(justify mirror)
			)
		)
		(property "Tolerance" ""
			(at 93.8 173.275 0)
			(layer "B.Fab")
			(hide yes)
			(effects
				(font
					(size 1 1)
					(thickness 0.15)
				)
				(justify mirror)
			)
		)
		(property "Val" "0R"
			(at 93.8 173.275 0)
			(layer "B.Fab")
			(hide yes)
			(effects
				(font
					(size 1 1)
					(thickness 0.15)
				)
				(justify mirror)
			)
		)
		(sheetname "Ethernet")
		(sheetfile "ethernet.kicad_sch")
		(attr smd)
		(fp_rect
			(start -0.925 0.47)
			(end 0.925 -0.47)
			(stroke
				(width 0.05)
				(type default)
			)
			(fill none)
			(layer "B.CrtYd")
		)
		(fp_rect
			(start -0.5 0.25)
			(end 0.5 -0.25)
			(stroke
				(width 0.15)
				(type solid)
			)
			(fill none)
			(layer "B.Fab")
		)
		(fp_text user "${REFERENCE}"
			(at -0.95 -3.168 0)
			(layer "B.Fab")
			(hide yes)
			(effects
				(font
					(size 0.7 0.7)
					(thickness 0.15)
				)
				(justify left bottom mirror)
			)
		)
		(fp_text user "License: Apache-2.0"
			(at -0.95 -5.169 0)
			(layer "B.Fab")
			(hide yes)
			(effects
				(font
					(size 0.7 0.7)
					(thickness 0.15)
				)
				(justify left bottom mirror)
			)
		)
		(fp_text user "Author: Antmicro"
			(at -0.95 -4.169 0)
			(layer "B.Fab")
			(hide yes)
			(effects
				(font
					(size 0.7 0.7)
					(thickness 0.15)
				)
				(justify left bottom mirror)
			)
		)
		(pad "1" smd roundrect
			(at -0.48 0 180)
			(size 0.59 0.64)
			(layers "B.Cu" "B.Paste" "B.Mask")
			(roundrect_rratio 0.25)
			(net 567 "/Ethernet/MPS_DUTY")
			(pintype "passive")
		)
		(pad "2" smd roundrect
			(at 0.48 0 180)
			(size 0.59 0.64)
			(layers "B.Cu" "B.Paste" "B.Mask")
			(roundrect_rratio 0.25)
			(net 499 "/Ethernet/VSS")
			(pintype "passive")
		)
	)
	(footprint "antmicro-footprints:R_0402_1005Metric"
		(layer "B.Cu")
		(at 73.975 110.625 90)
		(descr "Resistor SMD 0402")
		(tags "resistor SMD 0402")
		(property "Reference" "R75"
			(at 0.125 -0.35 -90)
			(layer "B.SilkS")
			(effects
				(font
					(size 0.7 0.7)
					(thickness 0.15)
				)
				(justify left bottom mirror)
			)
		)
		(property "Value" "R_0R_0402"
			(at 0 -1.4 -90)
			(layer "B.Fab")
			(effects
				(font
					(size 0.7 0.7)
					(thickness 0.15)
				)
				(justify left bottom mirror)
			)
		)
		(property "Footprint" "antmicro-footprints:R_0402_1005Metric"
			(at 0 0 90)
			(layer "F.Fab")
			(hide yes)
			(effects
				(font
					(size 1.27 1.27)
					(thickness 0.15)
				)
			)
		)
		(property "Datasheet" "https://industrial.panasonic.com/cdbs/www-data/pdf/RDA0000/AOA0000C301.pdf"
			(at 0 0 90)
			(layer "F.Fab")
			(hide yes)
			(effects
				(font
					(size 1.27 1.27)
					(thickness 0.15)
				)
			)
		)
		(property "Author" "Antmicro"
			(at 184.6 36.65 0)
			(layer "B.Fab")
			(hide yes)
			(effects
				(font
					(size 1 1)
					(thickness 0.15)
				)
				(justify mirror)
			)
		)
		(property "Current" "1A"
			(at 184.6 36.65 0)
			(layer "B.Fab")
			(hide yes)
			(effects
				(font
					(size 1 1)
					(thickness 0.15)
				)
				(justify mirror)
			)
		)
		(property "License" "Apache-2.0"
			(at 184.6 36.65 0)
			(layer "B.Fab")
			(hide yes)
			(effects
				(font
					(size 1 1)
					(thickness 0.15)
				)
				(justify mirror)
			)
		)
		(property "MPN" "ERJ2GE0R00X"
			(at 184.6 36.65 0)
			(layer "B.Fab")
			(hide yes)
			(effects
				(font
					(size 1 1)
					(thickness 0.15)
				)
				(justify mirror)
			)
		)
		(property "Manufacturer" "Panasonic"
			(at 184.6 36.65 0)
			(layer "B.Fab")
			(hide yes)
			(effects
				(font
					(size 1 1)
					(thickness 0.15)
				)
				(justify mirror)
			)
		)
		(property "Tolerance" ""
			(at 184.6 36.65 0)
			(layer "B.Fab")
			(hide yes)
			(effects
				(font
					(size 1 1)
					(thickness 0.15)
				)
				(justify mirror)
			)
		)
		(property "Val" "0R"
			(at 184.6 36.65 0)
			(layer "B.Fab")
			(hide yes)
			(effects
				(font
					(size 1 1)
					(thickness 0.15)
				)
				(justify mirror)
			)
		)
		(sheetname "USB Debug, DP")
		(sheetfile "usb.kicad_sch")
		(attr smd)
		(fp_rect
			(start -0.925 0.47)
			(end 0.925 -0.47)
			(stroke
				(width 0.05)
				(type default)
			)
			(fill none)
			(layer "B.CrtYd")
		)
		(fp_rect
			(start -0.5 0.25)
			(end 0.5 -0.25)
			(stroke
				(width 0.15)
				(type solid)
			)
			(fill none)
			(layer "B.Fab")
		)
		(fp_text user "${REFERENCE}"
			(at -0.95 -3.168 -90)
			(layer "B.Fab")
			(hide yes)
			(effects
				(font
					(size 0.7 0.7)
					(thickness 0.15)
				)
				(justify left bottom mirror)
			)
		)
		(fp_text user "License: Apache-2.0"
			(at -0.95 -5.169 -90)
			(layer "B.Fab")
			(hide yes)
			(effects
				(font
					(size 0.7 0.7)
					(thickness 0.15)
				)
				(justify left bottom mirror)
			)
		)
		(fp_text user "Author: Antmicro"
			(at -0.95 -4.169 -90)
			(layer "B.Fab")
			(hide yes)
			(effects
				(font
					(size 0.7 0.7)
					(thickness 0.15)
				)
				(justify left bottom mirror)
			)
		)
		(pad "1" smd roundrect
			(at -0.48 0 90)
			(size 0.59 0.64)
			(layers "B.Cu" "B.Paste" "B.Mask")
			(roundrect_rratio 0.25)
			(net 677 "USBC_HPD")
			(pintype "passive")
		)
		(pad "2" smd roundrect
			(at 0.48 0 90)
			(size 0.59 0.64)
			(layers "B.Cu" "B.Paste" "B.Mask")
			(roundrect_rratio 0.25)
			(net 502 "/USB Debug, DP/HPDIN")
			(pintype "passive")
		)
	)
)
